(kicad_pcb
	(version 20241229)
	(generator "pcbnew")
	(generator_version "9.0")
	(general
		(thickness 1.62)
		(legacy_teardrops no)
	)
	(paper "A3")
	(title_block
		(title "COM Express 7 Baseboard")
		(date "2025-02-04")
		(rev "1.1.2")
		(company "Antmicro Ltd")
		(comment 1 "www.antmicro.com")
		(comment 9 "footprints 311-314 of 802")
	)
	(layers
		(0 "F.Cu" signal)
		(4 "In1.Cu" signal)
		(6 "In2.Cu" signal)
		(8 "In3.Cu" signal)
		(10 "In4.Cu" signal)
		(12 "In5.Cu" signal)
		(14 "In6.Cu" signal)
		(2 "B.Cu" signal)
		(9 "F.Adhes" user "F.Adhesive")
		(11 "B.Adhes" user "B.Adhesive")
		(13 "F.Paste" user)
		(15 "B.Paste" user)
		(5 "F.SilkS" user "F.Silkscreen")
		(7 "B.SilkS" user "B.Silkscreen")
		(1 "F.Mask" user)
		(3 "B.Mask" user)
		(17 "Dwgs.User" user "User.Drawings")
		(19 "Cmts.User" user "User.Comments")
		(21 "Eco1.User" user "User.Eco1")
		(23 "Eco2.User" user "User.Eco2")
		(25 "Edge.Cuts" user)
		(27 "Margin" user)
		(31 "F.CrtYd" user "F.Courtyard")
		(29 "B.CrtYd" user "B.Courtyard")
		(35 "F.Fab" user)
		(33 "B.Fab" user)
	)
	(footprint "antmicro-footprints:USON-10_2.5x1mm_P0.5mm"
		(layer "F.Cu")
		(at 314.75 167.01)
		(descr "USON-10 2.5x1mm_ Pitch 0.5mm")
		(tags "USON-10 2.5x1mm Pitch 0.5mm")
		(property "Reference" "U13"
			(at -0.9 1.15 90)
			(layer "F.SilkS")
			(effects
				(font
					(size 0.7 0.7)
					(thickness 0.15)
				)
				(justify left bottom)
			)
		)
		(property "Value" "ESD204DQAR"
			(at 0.018 2.499 0)
			(layer "F.Fab")
			(effects
				(font
					(size 0.7 0.7)
					(thickness 0.15)
				)
				(justify left bottom)
			)
		)
		(property "Datasheet" "https://www.ti.com/lit/ds/symlink/esd204.pdf?ts=1706004844383&ref_url=https%253A%252F%252Fwww.ti.com%252Finterface%252Fdiodes%252Fesd-protection-diodes%252Fproducts.html"
			(at 0 0 0)
			(layer "F.Fab")
			(hide yes)
			(effects
				(font
					(size 1.27 1.27)
					(thickness 0.15)
				)
			)
		)
		(property "Author" "Antmicro"
			(at 0 0 0)
			(layer "F.Fab")
			(hide yes)
			(effects
				(font
					(size 1 1)
					(thickness 0.15)
				)
			)
		)
		(property "License" "Apache-2.0"
			(at 0 0 0)
			(layer "F.Fab")
			(hide yes)
			(effects
				(font
					(size 1 1)
					(thickness 0.15)
				)
			)
		)
		(property "MPN" "ESD204DQAR"
			(at 0 0 0)
			(layer "F.Fab")
			(hide yes)
			(effects
				(font
					(size 1 1)
					(thickness 0.15)
				)
			)
		)
		(property "Manufacturer" "Texas Instruments"
			(at 0 0 0)
			(layer "F.Fab")
			(hide yes)
			(effects
				(font
					(size 1 1)
					(thickness 0.15)
				)
			)
		)
		(sheetname "Backplane")
		(sheetfile "backplane.kicad_sch")
		(attr smd)
		(fp_line
			(start 0.498 -1.401)
			(end -0.5 -1.401)
			(stroke
				(width 0.15)
				(type solid)
			)
			(layer "F.SilkS")
		)
		(fp_line
			(start 0.498 1.398)
			(end -0.5 1.398)
			(stroke
				(width 0.15)
				(type solid)
			)
			(layer "F.SilkS")
		)
		(fp_circle
			(center -0.68 -1.27)
			(end -0.63 -1.27)
			(stroke
				(width 0.15)
				(type solid)
			)
			(fill yes)
			(layer "F.SilkS")
		)
		(fp_rect
			(start -0.8 -1.5)
			(end 0.8 1.499)
			(stroke
				(width 0.05)
				(type solid)
			)
			(fill no)
			(layer "F.CrtYd")
		)
		(fp_line
			(start -0.5 -1)
			(end -0.5 1.249)
			(stroke
				(width 0.15)
				(type solid)
			)
			(layer "F.Fab")
		)
		(fp_line
			(start -0.5 1.249)
			(end 0.498 1.249)
			(stroke
				(width 0.15)
				(type solid)
			)
			(layer "F.Fab")
		)
		(fp_line
			(start -0.25 -1.25)
			(end -0.5 -1)
			(stroke
				(width 0.15)
				(type solid)
			)
			(layer "F.Fab")
		)
		(fp_line
			(start 0.498 -1.25)
			(end -0.25 -1.25)
			(stroke
				(width 0.15)
				(type solid)
			)
			(layer "F.Fab")
		)
		(fp_line
			(start 0.498 -1.25)
			(end 0.498 1.249)
			(stroke
				(width 0.15)
				(type solid)
			)
			(layer "F.Fab")
		)
		(pad "1" smd roundrect
			(at -0.387 -1 270)
			(size 0.25 0.55)
			(layers "F.Cu" "F.Mask" "F.Paste")
			(roundrect_rratio 0.25)
			(net 995 "unconnected-(U13-Pad1)_1")
			(pintype "passive+no_connect")
			(teardrops
				(best_length_ratio 0.2)
				(max_length 1)
				(best_width_ratio 0.9)
				(max_width 2)
				(curved_edges yes)
				(filter_ratio 0.9)
				(enabled yes)
				(allow_two_segments yes)
				(prefer_zone_connections yes)
			)
		)
		(pad "2" smd roundrect
			(at -0.387 -0.5 270)
			(size 0.25 0.55)
			(layers "F.Cu" "F.Mask" "F.Paste")
			(roundrect_rratio 0.25)
			(net 972 "unconnected-(U13-Pad2)")
			(pintype "passive+no_connect")
			(teardrops
				(best_length_ratio 0.2)
				(max_length 1)
				(best_width_ratio 0.9)
				(max_width 2)
				(curved_edges yes)
				(filter_ratio 0.9)
				(enabled yes)
				(allow_two_segments yes)
				(prefer_zone_connections yes)
			)
		)
		(pad "3" smd roundrect
			(at -0.387 0 270)
			(size 0.4 0.55)
			(layers "F.Cu" "F.Mask" "F.Paste")
			(roundrect_rratio 0.25)
			(net 1 "GND")
			(pintype "power_in")
			(teardrops
				(best_length_ratio 0.2)
				(max_length 1)
				(best_width_ratio 0.9)
				(max_width 2)
				(curved_edges yes)
				(filter_ratio 0.9)
				(enabled yes)
				(allow_two_segments yes)
				(prefer_zone_connections yes)
			)
		)
		(pad "4" smd roundrect
			(at -0.387 0.498 270)
			(size 0.25 0.55)
			(layers "F.Cu" "F.Mask" "F.Paste")
			(roundrect_rratio 0.25)
			(net 208 "/Backplane/UART.RX")
			(pintype "passive")
			(teardrops
				(best_length_ratio 0.2)
				(max_length 1)
				(best_width_ratio 0.9)
				(max_width 2)
				(curved_edges yes)
				(filter_ratio 0.9)
				(enabled yes)
				(allow_two_segments yes)
				(prefer_zone_connections yes)
			)
		)
		(pad "5" smd roundrect
			(at -0.387 0.998 270)
			(size 0.25 0.55)
			(layers "F.Cu" "F.Mask" "F.Paste")
			(roundrect_rratio 0.25)
			(net 207 "/Backplane/UART.TX")
			(pintype "passive")
			(teardrops
				(best_length_ratio 0.2)
				(max_length 1)
				(best_width_ratio 0.9)
				(max_width 2)
				(curved_edges yes)
				(filter_ratio 0.9)
				(enabled yes)
				(allow_two_segments yes)
				(prefer_zone_connections yes)
			)
		)
		(pad "6" smd roundrect
			(at 0.385 0.998 270)
			(size 0.25 0.55)
			(layers "F.Cu" "F.Mask" "F.Paste")
			(roundrect_rratio 0.25)
			(net 207 "/Backplane/UART.TX")
			(pintype "passive")
			(teardrops
				(best_length_ratio 0.2)
				(max_length 1)
				(best_width_ratio 0.9)
				(max_width 2)
				(curved_edges yes)
				(filter_ratio 0.9)
				(enabled yes)
				(allow_two_segments yes)
				(prefer_zone_connections yes)
			)
		)
		(pad "7" smd roundrect
			(at 0.385 0.498 270)
			(size 0.25 0.55)
			(layers "F.Cu" "F.Mask" "F.Paste")
			(roundrect_rratio 0.25)
			(net 208 "/Backplane/UART.RX")
			(pintype "passive")
			(teardrops
				(best_length_ratio 0.2)
				(max_length 1)
				(best_width_ratio 0.9)
				(max_width 2)
				(curved_edges yes)
				(filter_ratio 0.9)
				(enabled yes)
				(allow_two_segments yes)
				(prefer_zone_connections yes)
			)
		)
		(pad "8" smd roundrect
			(at 0.385 0 270)
			(size 0.4 0.55)
			(layers "F.Cu" "F.Mask" "F.Paste")
			(roundrect_rratio 0.25)
			(net 1 "GND")
			(pintype "passive")
			(teardrops
				(best_length_ratio 0.2)
				(max_length 1)
				(best_width_ratio 0.9)
				(max_width 2)
				(curved_edges yes)
				(filter_ratio 0.9)
				(enabled yes)
				(allow_two_segments yes)
				(prefer_zone_connections yes)
			)
		)
		(pad "9" smd roundrect
			(at 0.385 -0.5 270)
			(size 0.25 0.55)
			(layers "F.Cu" "F.Mask" "F.Paste")
			(roundrect_rratio 0.25)
			(net 994 "unconnected-(U13-Pad2)_1")
			(pintype "passive+no_connect")
			(teardrops
				(best_length_ratio 0.2)
				(max_length 1)
				(best_width_ratio 0.9)
				(max_width 2)
				(curved_edges yes)
				(filter_ratio 0.9)
				(enabled yes)
				(allow_two_segments yes)
				(prefer_zone_connections yes)
			)
		)
		(pad "10" smd roundrect
			(at 0.385 -1 270)
			(size 0.25 0.55)
			(layers "F.Cu" "F.Mask" "F.Paste")
			(roundrect_rratio 0.25)
			(net 971 "unconnected-(U13-Pad1)")
			(pintype "passive+no_connect")
			(teardrops
				(best_length_ratio 0.2)
				(max_length 1)
				(best_width_ratio 0.9)
				(max_width 2)
				(curved_edges yes)
				(filter_ratio 0.9)
				(enabled yes)
				(allow_two_segments yes)
				(prefer_zone_connections yes)
			)
		)
	)
	(footprint "antmicro-footprints:R_0402_1005Metric"
		(layer "F.Cu")
		(at 124.84 134.88 180)
		(descr "Resistor SMD 0402")
		(tags "resistor SMD 0402")
		(property "Reference" "R304"
			(at 0.79 -0.43 0)
			(layer "F.SilkS")
			(effects
				(font
					(size 0.7 0.7)
					(thickness 0.15)
				)
				(justify right bottom)
			)
		)
		(property "Value" "R_10k_0402"
			(at -1.011843 1.772047 0)
			(layer "F.Fab")
			(effects
				(font
					(size 0.7 0.7)
					(thickness 0.15)
				)
				(justify right bottom)
			)
		)
		(property "Datasheet" "https://www.bourns.com/docs/product-datasheets/cr.pdf"
			(at 0 0 180)
			(layer "F.Fab")
			(hide yes)
			(effects
				(font
					(size 1.27 1.27)
					(thickness 0.15)
				)
			)
		)
		(property "Author" "Antmicro"
			(at 249.68 269.76 0)
			(layer "F.Fab")
			(hide yes)
			(effects
				(font
					(size 1 1)
					(thickness 0.15)
				)
			)
		)
		(property "License" "Apache-2.0"
			(at 249.68 269.76 0)
			(layer "F.Fab")
			(hide yes)
			(effects
				(font
					(size 1 1)
					(thickness 0.15)
				)
			)
		)
		(property "MPN" "CR0402-FX-1002GLF"
			(at 249.68 269.76 0)
			(layer "F.Fab")
			(hide yes)
			(effects
				(font
					(size 1 1)
					(thickness 0.15)
				)
			)
		)
		(property "Manufacturer" "Bourns"
			(at 249.68 269.76 0)
			(layer "F.Fab")
			(hide yes)
			(effects
				(font
					(size 1 1)
					(thickness 0.15)
				)
			)
		)
		(property "Public" "False"
			(at 249.68 269.76 0)
			(layer "F.Fab")
			(hide yes)
			(effects
				(font
					(size 1 1)
					(thickness 0.15)
				)
			)
		)
		(property "Tolerance" "1%"
			(at 249.68 269.76 0)
			(layer "F.Fab")
			(hide yes)
			(effects
				(font
					(size 1 1)
					(thickness 0.15)
				)
			)
		)
		(property "Val" "10k"
			(at 249.68 269.76 0)
			(layer "F.Fab")
			(hide yes)
			(effects
				(font
					(size 1 1)
					(thickness 0.15)
				)
			)
		)
		(sheetname "KR to SFI #2")
		(sheetfile "kr_sfi.kicad_sch")
		(attr smd dnp)
		(fp_rect
			(start -0.925 -0.47)
			(end 0.925 0.47)
			(stroke
				(width 0.05)
				(type default)
			)
			(fill no)
			(layer "F.CrtYd")
		)
		(fp_rect
			(start -0.5 -0.25)
			(end 0.5 0.25)
			(stroke
				(width 0.15)
				(type solid)
			)
			(fill no)
			(layer "F.Fab")
		)
		(pad "1" smd roundrect
			(at -0.48 0 180)
			(size 0.59 0.64)
			(layers "F.Cu" "F.Mask" "F.Paste")
			(roundrect_rratio 0.25)
			(net 684 "Net-(U45C-ST)")
			(pintype "passive")
			(teardrops
				(best_length_ratio 0.2)
				(max_length 1)
				(best_width_ratio 0.9)
				(max_width 2)
				(curved_edges yes)
				(filter_ratio 0.9)
				(enabled yes)
				(allow_two_segments yes)
				(prefer_zone_connections yes)
			)
		)
		(pad "2" smd roundrect
			(at 0.48 0 180)
			(size 0.59 0.64)
			(layers "F.Cu" "F.Mask" "F.Paste")
			(roundrect_rratio 0.25)
			(net 78 "+1V8")
			(pintype "passive")
			(teardrops
				(best_length_ratio 0.2)
				(max_length 1)
				(best_width_ratio 0.9)
				(max_width 2)
				(curved_edges yes)
				(filter_ratio 0.9)
				(enabled yes)
				(allow_two_segments yes)
				(prefer_zone_connections yes)
			)
		)
	)
	(footprint "antmicro-footprints:R_0201"
		(layer "F.Cu")
		(at 152.57 147.31 90)
		(descr "Resistor SMD 0201")
		(tags "resistor SMD 0201")
		(property "Reference" "R257"
			(at -4.125 0.28 90)
			(layer "F.SilkS")
			(effects
				(font
					(size 0.7 0.7)
					(thickness 0.15)
				)
				(justify left bottom)
			)
		)
		(property "Value" "R_0R_0201"
			(at 0 1.25 90)
			(layer "F.Fab")
			(effects
				(font
					(size 0.7 0.7)
					(thickness 0.15)
				)
				(justify left bottom)
			)
		)
		(property "Datasheet" "https://www.bourns.com/docs/product-datasheets/cr.pdf"
			(at 0 0 90)
			(layer "F.Fab")
			(hide yes)
			(effects
				(font
					(size 1.27 1.27)
					(thickness 0.15)
				)
			)
		)
		(property "Author" "Antmicro"
			(at 299.88 -5.26 0)
			(layer "F.Fab")
			(hide yes)
			(effects
				(font
					(size 1 1)
					(thickness 0.15)
				)
			)
		)
		(property "License" "Apache-2.0"
			(at 299.88 -5.26 0)
			(layer "F.Fab")
			(hide yes)
			(effects
				(font
					(size 1 1)
					(thickness 0.15)
				)
			)
		)
		(property "MPN" "CR0201-FX-0R00GLF"
			(at 299.88 -5.26 0)
			(layer "F.Fab")
			(hide yes)
			(effects
				(font
					(size 1 1)
					(thickness 0.15)
				)
			)
		)
		(property "Manufacturer" "Bourns"
			(at 299.88 -5.26 0)
			(layer "F.Fab")
			(hide yes)
			(effects
				(font
					(size 1 1)
					(thickness 0.15)
				)
			)
		)
		(property "Tolerance" "1%"
			(at 299.88 -5.26 0)
			(layer "F.Fab")
			(hide yes)
			(effects
				(font
					(size 1 1)
					(thickness 0.15)
				)
			)
		)
		(property "Val" "0R"
			(at 299.88 -5.26 0)
			(layer "F.Fab")
			(hide yes)
			(effects
				(font
					(size 1 1)
					(thickness 0.15)
				)
			)
		)
		(sheetname "KR to SFI #1")
		(sheetfile "kr_sfi.kicad_sch")
		(attr smd)
		(fp_rect
			(start -0.7 -0.35)
			(end 0.7 0.35)
			(stroke
				(width 0.05)
				(type default)
			)
			(fill no)
			(layer "F.CrtYd")
		)
		(fp_rect
			(start -0.3 -0.15)
			(end 0.298 0.148)
			(stroke
				(width 0.15)
				(type solid)
			)
			(fill no)
			(layer "F.Fab")
		)
		(pad "" smd roundrect
			(at -0.346 0 90)
			(size 0.318 0.36)
			(layers "F.Paste")
			(roundrect_rratio 0.25)
			(teardrops
				(best_length_ratio 0.2)
				(max_length 1)
				(best_width_ratio 0.9)
				(max_width 2)
				(curved_edges yes)
				(filter_ratio 0.9)
				(enabled yes)
				(allow_two_segments yes)
				(prefer_zone_connections yes)
			)
		)
		(pad "" smd roundrect
			(at 0.344 0 90)
			(size 0.318 0.36)
			(layers "F.Paste")
			(roundrect_rratio 0.25)
			(teardrops
				(best_length_ratio 0.2)
				(max_length 1)
				(best_width_ratio 0.9)
				(max_width 2)
				(curved_edges yes)
				(filter_ratio 0.9)
				(enabled yes)
				(allow_two_segments yes)
				(prefer_zone_connections yes)
			)
		)
		(pad "1" smd roundrect
			(at -0.32 0 90)
			(size 0.46 0.4)
			(layers "F.Cu" "F.Mask")
			(roundrect_rratio 0.25)
			(net 433 "/2xSFP+/10GKR_SFP0.RX-")
			(pintype "passive")
			(teardrops
				(best_length_ratio 0.2)
				(max_length 1)
				(best_width_ratio 0.9)
				(max_width 2)
				(curved_edges yes)
				(filter_ratio 0.9)
				(enabled yes)
				(allow_two_segments yes)
				(prefer_zone_connections yes)
			)
		)
		(pad "2" smd roundrect
			(at 0.32 0 90)
			(size 0.46 0.4)
			(layers "F.Cu" "F.Mask")
			(roundrect_rratio 0.25)
			(net 665 "/2xSFP+/KR to SFI #1/KR_R.RX-")
			(pintype "passive")
			(teardrops
				(best_length_ratio 0.2)
				(max_length 1)
				(best_width_ratio 0.9)
				(max_width 2)
				(curved_edges yes)
				(filter_ratio 0.9)
				(enabled yes)
				(allow_two_segments yes)
				(prefer_zone_connections yes)
			)
		)
	)
	(footprint "antmicro-footprints:R_0402_1005Metric"
		(layer "F.Cu")
		(at 113.7 78.71)
		(descr "Resistor SMD 0402")
		(tags "resistor SMD 0402")
		(property "Reference" "R71"
			(at -1 1.35 0)
			(layer "F.SilkS")
			(effects
				(font
					(size 0.7 0.7)
					(thickness 0.15)
				)
				(justify left bottom)
			)
		)
		(property "Value" "R_0R_0402"
			(at -1.011843 1.772047 0)
			(layer "F.Fab")
			(effects
				(font
					(size 0.7 0.7)
					(thickness 0.15)
				)
				(justify left bottom)
			)
		)
		(property "Datasheet" "https://industrial.panasonic.com/cdbs/www-data/pdf/RDA0000/AOA0000C301.pdf"
			(at 0 0 0)
			(layer "F.Fab")
			(hide yes)
			(effects
				(font
					(size 1.27 1.27)
					(thickness 0.15)
				)
			)
		)
		(property "Author" "Antmicro"
			(at 0 0 0)
			(layer "F.Fab")
			(hide yes)
			(effects
				(font
					(size 1 1)
					(thickness 0.15)
				)
			)
		)
		(property "Current" "1A"
			(at 0 0 0)
			(layer "F.Fab")
			(hide yes)
			(effects
				(font
					(size 1 1)
					(thickness 0.15)
				)
			)
		)
		(property "License" "Apache-2.0"
			(at 0 0 0)
			(layer "F.Fab")
			(hide yes)
			(effects
				(font
					(size 1 1)
					(thickness 0.15)
				)
			)
		)
		(property "MPN" "ERJ2GE0R00X"
			(at 0 0 0)
			(layer "F.Fab")
			(hide yes)
			(effects
				(font
					(size 1 1)
					(thickness 0.15)
				)
			)
		)
		(property "Manufacturer" "Panasonic"
			(at 0 0 0)
			(layer "F.Fab")
			(hide yes)
			(effects
				(font
					(size 1 1)
					(thickness 0.15)
				)
			)
		)
		(property "Public" "False"
			(at 0 0 0)
			(layer "F.Fab")
			(hide yes)
			(effects
				(font
					(size 1 1)
					(thickness 0.15)
				)
			)
		)
		(property "Tolerance" ""
			(at 0 0 0)
			(layer "F.Fab")
			(hide yes)
			(effects
				(font
					(size 1 1)
					(thickness 0.15)
				)
			)
		)
		(property "Val" "0R"
			(at 0 0 0)
			(layer "F.Fab")
			(hide yes)
			(effects
				(font
					(size 1 1)
					(thickness 0.15)
				)
			)
		)
		(sheetname "USB-C console")
		(sheetfile "usb-c_console.kicad_sch")
		(attr smd)
		(fp_rect
			(start -0.925 -0.47)
			(end 0.925 0.47)
			(stroke
				(width 0.05)
				(type default)
			)
			(fill no)
			(layer "F.CrtYd")
		)
		(fp_rect
			(start -0.5 -0.25)
			(end 0.5 0.25)
			(stroke
				(width 0.15)
				(type solid)
			)
			(fill no)
			(layer "F.Fab")
		)
		(pad "1" smd roundrect
			(at -0.48 0)
			(size 0.59 0.64)
			(layers "F.Cu" "F.Mask" "F.Paste")
			(roundrect_rratio 0.25)
			(net 57 "/USB-C console/FTDI_VCCIO")
			(pintype "passive")
			(teardrops
				(best_length_ratio 0.2)
				(max_length 1)
				(best_width_ratio 0.9)
				(max_width 2)
				(curved_edges yes)
				(filter_ratio 0.9)
				(enabled yes)
				(allow_two_segments yes)
				(prefer_zone_connections yes)
			)
		)
		(pad "2" smd roundrect
			(at 0.48 0)
			(size 0.59 0.64)
			(layers "F.Cu" "F.Mask" "F.Paste")
			(roundrect_rratio 0.25)
			(net 570 "Net-(U6-~{RESET})")
			(pintype "passive")
			(teardrops
				(best_length_ratio 0.2)
				(max_length 1)
				(best_width_ratio 0.9)
				(max_width 2)
				(curved_edges yes)
				(filter_ratio 0.9)
				(enabled yes)
				(allow_two_segments yes)
				(prefer_zone_connections yes)
			)
		)
	)
)
